#ISCELL
  pure_quanta quanta_title_block_c *
  *
#CELL
  pure_quanta genoa_sp5 *
  page24_i148
#CELL
  pure_quanta genoa_sp5 *
  page24_i149
#ISCELL
  standard offpage *
  page24_i218
#ISCELL
  standard offpage *
  page24_i219
#ISCELL
  mstr_standard tap *
  page24_i220
#ISCELL
  mstr_standard tap *
  page24_i221
#ISCELL
  mstr_standard tap *
  page24_i222
#ISCELL
  mstr_standard tap *
  page24_i223
#ISCELL
  standard tap *
  page24_i224
#ISCELL
  standard tap *
  page24_i225
#ISCELL
  standard tap *
  page24_i226
#ISCELL
  standard tap *
  page24_i227
#ISCELL
  standard tap *
  page24_i228
#ISCELL
  standard tap *
  page24_i229
#ISCELL
  standard tap *
  page24_i230
#ISCELL
  standard tap *
  page24_i231
#ISCELL
  standard tap *
  page24_i232
#ISCELL
  standard tap *
  page24_i233
#ISCELL
  standard tap *
  page24_i234
#ISCELL
  standard tap *
  page24_i235
#ISCELL
  standard tap *
  page24_i236
#ISCELL
  standard tap *
  page24_i237
#ISCELL
  standard tap *
  page24_i238
#ISCELL
  standard tap *
  page24_i239
#ISCELL
  standard tap *
  page24_i240
#ISCELL
  standard tap *
  page24_i241
#ISCELL
  standard tap *
  page24_i242
#ISCELL
  standard tap *
  page24_i243
#ISCELL
  standard tap *
  page24_i244
#ISCELL
  standard tap *
  page24_i245
#ISCELL
  standard tap *
  page24_i246
#ISCELL
  standard tap *
  page24_i247
#ISCELL
  standard tap *
  page24_i248
#ISCELL
  standard tap *
  page24_i249
#ISCELL
  standard tap *
  page24_i250
#ISCELL
  standard tap *
  page24_i251
#ISCELL
  standard tap *
  page24_i292
#ISCELL
  standard tap *
  page24_i293
#ISCELL
  standard tap *
  page24_i294
#ISCELL
  standard tap *
  page24_i295
#ISCELL
  standard tap *
  page24_i296
#ISCELL
  standard tap *
  page24_i297
#ISCELL
  standard tap *
  page24_i298
#ISCELL
  standard tap *
  page24_i299
#ISCELL
  standard tap *
  page24_i300
#ISCELL
  standard tap *
  page24_i301
#ISCELL
  standard tap *
  page24_i302
#ISCELL
  standard tap *
  page24_i303
#ISCELL
  standard tap *
  page24_i304
#ISCELL
  standard tap *
  page24_i305
#ISCELL
  standard offpage *
  page24_i306
#ISCELL
  standard offpage *
  page24_i307
#ISCELL
  standard tap *
  page24_i308
#ISCELL
  standard tap *
  page24_i309
#ISCELL
  standard tap *
  page24_i310
#ISCELL
  standard tap *
  page24_i311
#ISCELL
  standard tap *
  page24_i312
#ISCELL
  standard tap *
  page24_i313
#ISCELL
  standard tap *
  page24_i314
#ISCELL
  standard tap *
  page24_i315
#ISCELL
  standard tap *
  page24_i316
#ISCELL
  standard tap *
  page24_i317
#ISCELL
  standard tap *
  page24_i318
#ISCELL
  standard tap *
  page24_i319
#ISCELL
  mstr_standard tap *
  page24_i320
#ISCELL
  standard tap *
  page24_i321
#ISCELL
  mstr_standard tap *
  page24_i322
#ISCELL
  mstr_standard tap *
  page24_i323
#ISCELL
  mstr_standard tap *
  page24_i324
#ISCELL
  mstr_standard tap *
  page24_i325
#ISCELL
  standard tap *
  page24_i326
#ISCELL
  standard tap *
  page24_i327
#ISCELL
  mstr_standard tap *
  page24_i328
#ISCELL
  mstr_standard tap *
  page24_i329
#ISCELL
  mstr_standard tap *
  page24_i330
#ISCELL
  standard tap *
  page24_i331
#ISCELL
  mstr_standard tap *
  page24_i332
#ISCELL
  mstr_standard tap *
  page24_i333
#ISCELL
  standard tap *
  page24_i334
#ISCELL
  standard tap *
  page24_i335
#ISCELL
  standard tap *
  page24_i336
#ISCELL
  standard tap *
  page24_i337
#ISCELL
  standard tap *
  page24_i338
#ISCELL
  standard tap *
  page24_i339
#ISCELL
  standard tap *
  page24_i340
#ISCELL
  standard tap *
  page24_i341
#ISCELL
  standard tap *
  page24_i342
#ISCELL
  standard tap *
  page24_i343
#ISCELL
  standard tap *
  page24_i344
#ISCELL
  standard tap *
  page24_i345
#ISCELL
  standard tap *
  page24_i346
#ISCELL
  standard tap *
  page24_i347
#ISCELL
  standard tap *
  page24_i348
#ISCELL
  standard tap *
  page24_i349
#ISCELL
  standard tap *
  page24_i350
#ISCELL
  standard tap *
  page24_i351
#ISCELL
  standard tap *
  page24_i352
#ISCELL
  standard tap *
  page24_i353
#ISCELL
  standard tap *
  page24_i354
#ISCELL
  standard tap *
  page24_i355
#ISCELL
  standard tap *
  page24_i356
#ISCELL
  standard tap *
  page24_i357
#ISCELL
  standard offpage *
  page24_i358
#ISCELL
  standard offpage *
  page24_i359
#ISCELL
  mstr_standard tap *
  page24_i360
#ISCELL
  mstr_standard tap *
  page24_i361
#ISCELL
  standard tap *
  page24_i362
#ISCELL
  mstr_standard tap *
  page24_i363
#ISCELL
  mstr_standard tap *
  page24_i364
#ISCELL
  standard tap *
  page24_i365
#ISCELL
  standard tap *
  page24_i366
#ISCELL
  standard tap *
  page24_i367
#ISCELL
  standard tap *
  page24_i368
#ISCELL
  standard tap *
  page24_i369
#ISCELL
  standard tap *
  page24_i370
#ISCELL
  standard tap *
  page24_i371
#ISCELL
  standard tap *
  page24_i372
#ISCELL
  standard tap *
  page24_i373
#ISCELL
  standard tap *
  page24_i374
#ISCELL
  standard tap *
  page24_i375
#ISCELL
  standard tap *
  page24_i376
#ISCELL
  standard tap *
  page24_i377
#ISCELL
  standard tap *
  page24_i378
#ISCELL
  standard tap *
  page24_i379
#ISCELL
  standard tap *
  page24_i380
#ISCELL
  standard tap *
  page24_i381
#ISCELL
  standard tap *
  page24_i382
#ISCELL
  standard tap *
  page24_i383
#ISCELL
  standard tap *
  page24_i384
#ISCELL
  standard tap *
  page24_i385
#ISCELL
  standard tap *
  page24_i386
#ISCELL
  standard tap *
  page24_i387
#ISCELL
  standard tap *
  page24_i388
#ISCELL
  standard tap *
  page24_i389
#ISCELL
  standard tap *
  page24_i390
#ISCELL
  standard tap *
  page24_i391
#ISCELL
  standard offpage *
  page24_i392
#ISCELL
  standard offpage *
  page24_i393
